FILE_TYPE=LIBRARY_PARTS;
primitive 'LED';
  pin
    'C':
      PIN_NUMBER='(1)';
      PINUSE='UNSPEC';
      NO_LOAD_CHECK='BOTH';
      NO_IO_CHECK='BOTH';
      ALLOW_CONNECT='TRUE';
    'A':
      PIN_NUMBER='(2)';
      PINUSE='UNSPEC';
      NO_LOAD_CHECK='BOTH';
      NO_IO_CHECK='BOTH';
      ALLOW_CONNECT='TRUE';
  end_pin;
  body
    PART_NAME='LED';
    PHYS_DES_PREFIX='DS';
  end_body;
end_primitive;
primitive 'LED_1NC','LED_1NCLF';
  pin
    'C':
      PIN_NUMBER='(1)';
      PINUSE='UNSPEC';
      NO_LOAD_CHECK='BOTH';
      NO_IO_CHECK='BOTH';
      ALLOW_CONNECT='TRUE';
    'A':
      PIN_NUMBER='(2)';
      PINUSE='UNSPEC';
      NO_LOAD_CHECK='BOTH';
      NO_IO_CHECK='BOTH';
      ALLOW_CONNECT='TRUE';
  end_pin;
  body
    NC_PINS='(3)';
    PART_NAME='LED';
    PHYS_DES_PREFIX='DS';
  end_body;
end_primitive;
primitive 'LED_A1LF','LED_A1';
  pin
    'C':
      PIN_NUMBER='(2)';
      PINUSE='UNSPEC';
      NO_LOAD_CHECK='BOTH';
      NO_IO_CHECK='BOTH';
      ALLOW_CONNECT='TRUE';
    'A':
      PIN_NUMBER='(1)';
      PINUSE='UNSPEC';
      NO_LOAD_CHECK='BOTH';
      NO_IO_CHECK='BOTH';
      ALLOW_CONNECT='TRUE';
  end_pin;
  body
    PART_NAME='LED';
    PHYS_DES_PREFIX='DS';
  end_body;
end_primitive;

END.
